FILE_TYPE = CONNECTIVITY;
{Allegro Design Entry HDL 17.4-2019 S026 (4007227) 1/17/2022}
"PAGE_NUMBER" = 251;
0"NC";
1"GND\g";
2"P3V3_AUX\g";
3"GND\g";
4"GND\g";
5"GND\g";
6"GND\g";
7"SMB_VR_SENSOR_3V3AUX_SDA"CDS_PHYS_NET_NAME"SMB_VR_SENSOR_3V3AUX_SDA";
8"SMB_VR_SENSOR_3V3AUX_SCL"CDS_PHYS_NET_NAME"SMB_VR_SENSOR_3V3AUX_SCL";
9"P3V3_AUX\g";
10"SMB_ADC_SCL_R";
11"SMB_ADC_SDA_R";
12"SMB_VR_3V3AUX_SDA"CDS_PHYS_NET_NAME"SMB_VR_3V3AUX_SDA";
13"SMB_VR_3V3AUX_SCL"CDS_PHYS_NET_NAME"SMB_VR_3V3AUX_SCL";
14"PCA9548_PCIE0_ADDR0";
15"PCA9548_PCIE0_ADDR1";
16"SMB_ADC_SCL_R";
17"SMB_LM75_0_3V3AUX_SCL"CDS_PHYS_NET_NAME"SMB_LM75_0_3V3AUX_SCL";
18"SMB_LM75_1_3V3AUX_SCL"CDS_PHYS_NET_NAME"SMB_LM75_1_3V3AUX_SCL";
19"SMB_LM75_2_3V3AUX_SDA"CDS_PHYS_NET_NAME"SMB_LM75_2_3V3AUX_SDA";
20"P3V3_AUX\g";
21"P3V3_AUX\g";
22"SMB_LM75_0_3V3AUX_SDA"CDS_PHYS_NET_NAME"SMB_LM75_0_3V3AUX_SDA";
23"SMB_LM75_1_3V3AUX_SDA"CDS_PHYS_NET_NAME"SMB_LM75_1_3V3AUX_SDA";
24"SMB_LM75_3_3V3AUX_SCL"CDS_PHYS_NET_NAME"SMB_LM75_3_3V3AUX_SCL";
25"SMB_LM75_2_3V3AUX_SCL"CDS_PHYS_NET_NAME"SMB_LM75_2_3V3AUX_SCL";
26"SMB_VR_SENSOR_3V3AUX_SCL"CDS_PHYS_NET_NAME"SMB_VR_SENSOR_3V3AUX_SCL";
27"SMB_ADC_SDA";
28"SMB_ADC_SCL";
29"SMB_P12V_HSC_SCL_R";
30"SMB_P12V_HSC_SDA_R";
31"SMB_LM75_3_3V3AUX_SCL_R"CDS_PHYS_NET_NAME"SMB_LM75_3_3V3AUX_SCL_R";
32"SMB_P12V_HSC_SCL";
33"SMB_LM75_3_3V3AUX_SDA_R"CDS_PHYS_NET_NAME"SMB_LM75_3_3V3AUX_SDA_R";
34"SMB_ADC_SDA_R";
35"SMB_P12V_HSC_SDA";
36"SMB_LM75_2_3V3AUX_SDA_R"CDS_PHYS_NET_NAME"SMB_LM75_2_3V3AUX_SDA_R";
37"SMB_LM75_2_3V3AUX_SCL_R"CDS_PHYS_NET_NAME"SMB_LM75_2_3V3AUX_SCL_R";
38"SMB_LM75_0_3V3AUX_SDA_R"CDS_PHYS_NET_NAME"SMB_LM75_0_3V3AUX_SDA_R";
39"SMB_LM75_0_3V3AUX_SCL_R"CDS_PHYS_NET_NAME"SMB_LM75_0_3V3AUX_SCL_R";
40"SMB_VR_3V3AUX_SCL_R6"CDS_PHYS_NET_NAME"SMB_VR_3V3AUX_SCL_R6";
41"SMB_VR_3V3AUX_SDA_R6"CDS_PHYS_NET_NAME"SMB_VR_3V3AUX_SDA_R6";
42"SMB_VR_3V3AUX_SDA"CDS_PHYS_NET_NAME"SMB_VR_3V3AUX_SDA";
43"SMB_VR_3V3AUX_SCL"CDS_PHYS_NET_NAME"SMB_VR_3V3AUX_SCL";
44"SMB_LM75_0_3V3AUX_SDA"CDS_PHYS_NET_NAME"SMB_LM75_0_3V3AUX_SDA";
45"SMB_LM75_0_3V3AUX_SCL"CDS_PHYS_NET_NAME"SMB_LM75_0_3V3AUX_SCL";
46"SMB_LM75_2_3V3AUX_SCL"CDS_PHYS_NET_NAME"SMB_LM75_2_3V3AUX_SCL";
47"SMB_LM75_2_3V3AUX_SDA"CDS_PHYS_NET_NAME"SMB_LM75_2_3V3AUX_SDA";
48"SMB_LM75_1_3V3AUX_SCL"CDS_PHYS_NET_NAME"SMB_LM75_1_3V3AUX_SCL";
49"SMB_LM75_1_3V3AUX_SDA"CDS_PHYS_NET_NAME"SMB_LM75_1_3V3AUX_SDA";
50"SMB_LM75_1_3V3AUX_SDA_R"CDS_PHYS_NET_NAME"SMB_LM75_1_3V3AUX_SDA_R";
51"SMB_LM75_1_3V3AUX_SCL_R"CDS_PHYS_NET_NAME"SMB_LM75_1_3V3AUX_SCL_R";
52"PU_RST_SMB_PCIE2_N"CDS_PHYS_NET_NAME"PU_RST_SMB_PCIE2_N";
53"PCA9548_PCIE0_ADDR1";
54"PCA9548_PCIE0_ADDR0";
55"SMB_LM75_3_3V3AUX_SDA"CDS_PHYS_NET_NAME"SMB_LM75_3_3V3AUX_SDA";
56"RST_SMB_SWITCH_N"CDS_PHYS_NET_NAME"RST_SMB_SWITCH_N";
57"SMB_VR_SENSOR_3V3AUX_SDA"CDS_PHYS_NET_NAME"SMB_VR_SENSOR_3V3AUX_SDA";
58"SMB_VR_SENSOR_3V3AUX_SDA_R"CDS_PHYS_NET_NAME"SMB_VR_SENSOR_3V3AUX_SDA_R";
59"SMB_LM75_3_3V3AUX_SDA"CDS_PHYS_NET_NAME"SMB_LM75_3_3V3AUX_SDA";
60"SMB_VR_SENSOR_3V3AUX_SCL_R"CDS_PHYS_NET_NAME"SMB_VR_SENSOR_3V3AUX_SCL_R";
61"PCA9548_PCIE0_ADDR2"CDS_PHYS_NET_NAME"PCA9548_PCIE0_ADDR2";
62"SMB_LM75_3_3V3AUX_SCL"CDS_PHYS_NET_NAME"SMB_LM75_3_3V3AUX_SCL";
63"PCA9548_PCIE0_ADDR2";
%"Q_RES"
"2","(-6575,2200)","0","pure_quanta","I1";
;
LOCATION"R3704"
$SEC"1"
CDS_SEC"1"
TOLERANCE"1%"
MATERIAL"CHIP"
PACK_TYPE"0402LF"
VALUE"1K"
WATTAGE"1/16W"
CDS_LIB"pure_quanta"
PART_NUMBER"CS21002FB06";
"A"
$PN"1"63;
"B"
$PN"2"1;
%"Q_RES"
"2","(-6025,2850)","0","pure_quanta","I10";
;
LOCATION"R3708"
$SEC"1"
CDS_SEC"1"
WATTAGE"1/16W"
VALUE"10K"
TOLERANCE"1%"
MATERIAL"EMPTY"
PACK_TYPE"0402LF"
CDS_LIB"pure_quanta"
PART_NUMBER"CS31002FB08";
"A"
$PN"1"20;
"B"
$PN"2"14;
%"Q_RES"
"1","(-5600,3950)","2","pure_quanta","I18";
;
LOCATION"R3719"
$SEC"1"
CDS_SEC"1"
VALUE"0"
MATERIAL"CHIP"
TOLERANCE"5%"
PACK_TYPE"0402LF"
WATTAGE"1/16W"
CDS_LIB"pure_quanta"
PART_NUMBER"CS00002JB13";
"B"
$PN"2"46;
"A"
$PN"1"37;
%"Q_RES"
"1","(-5600,4000)","2","pure_quanta","I19";
;
LOCATION"R3720"
$SEC"1"
CDS_SEC"1"
VALUE"0"
TOLERANCE"5%"
MATERIAL"CHIP"
CDS_LIB"pure_quanta"
PACK_TYPE"0402LF"
WATTAGE"1/16W"
PART_NUMBER"CS00002JB13";
"B"
$PN"2"47;
"A"
$PN"1"36;
%"UNIVERSAL_GND"
"1","(-6575,1975)","0","pure_quanta_power","I2";
;
ROOM"IO_SLOT"
CDS_LIB"pure_quanta_power"
HDL_POWER"GND";
"A"1;
%"Q_RES"
"1","(-5600,4050)","2","pure_quanta","I20";
;
LOCATION"R3717"
$SEC"1"
CDS_SEC"1"
VALUE"0"
TOLERANCE"5%"
MATERIAL"CHIP"
CDS_LIB"pure_quanta"
WATTAGE"1/16W"
PACK_TYPE"0402LF"
PART_NUMBER"CS00002JB13";
"B"
$PN"2"48;
"A"
$PN"1"51;
%"Q_RES"
"1","(-5600,4100)","2","pure_quanta","I21";
;
LOCATION"R3718"
$SEC"1"
CDS_SEC"1"
TOLERANCE"5%"
VALUE"0"
MATERIAL"CHIP"
WATTAGE"1/16W"
PACK_TYPE"0402LF"
CDS_LIB"pure_quanta"
PART_NUMBER"CS00002JB13";
"B"
$PN"2"49;
"A"
$PN"1"50;
%"Q_RES"
"2","(-6950,4750)","2","pure_quanta","I27";
;
LOCATION"R3705"
$SEC"1"
CDS_SEC"1"
WATTAGE"1/16W"
VALUE"10K"
PACK_TYPE"0402LF"
MATERIAL"EMPTY"
TOLERANCE"1%"
CDS_LIB"pure_quanta"
PART_NUMBER"CS31002FB08";
"A"
$PN"1"2;
"B"
$PN"2"56;
%"UNIVERSAL_POWER"
"1","(-6950,5025)","0","pure_quanta_power","I28";
;
HDL_POWER"P3V3_AUX"
CDS_LIB"pure_quanta_power";
"A"2;
%"Q_RES"
"1","(-5850,4400)","0","pure_quanta","I29";
;
LOCATION"R3710"
$SEC"1"
CDS_SEC"1"
VALUE"0"
MATERIAL"CHIP"
TOLERANCE"5%"
CDS_LIB"pure_quanta"
WATTAGE"1/16W"
PACK_TYPE"0402LF"
PART_NUMBER"CS00002JB13";
"B"
$PN"2"52;
"A"
$PN"1"56;
%"UNIVERSAL_GND"
"1","(-6300,1975)","0","pure_quanta_power","I3";
;
ROOM"IO_SLOT"
CDS_LIB"pure_quanta_power"
HDL_POWER"GND";
"A"3;
%"Q_RES"
"1","(-5600,4200)","2","pure_quanta","I30";
;
LOCATION"R3716"
$SEC"1"
CDS_SEC"1"
VALUE"0"
TOLERANCE"5%"
MATERIAL"CHIP"
WATTAGE"1/16W"
PACK_TYPE"0402LF"
CDS_LIB"pure_quanta"
PART_NUMBER"CS00002JB13";
"B"
$PN"2"44;
"A"
$PN"1"38;
%"Q_RES"
"1","(-5600,4150)","2","pure_quanta","I31";
;
LOCATION"R3715"
$SEC"1"
CDS_SEC"1"
TOLERANCE"5%"
VALUE"0"
MATERIAL"CHIP"
CDS_LIB"pure_quanta"
WATTAGE"1/16W"
PACK_TYPE"0402LF"
PART_NUMBER"CS00002JB13";
"B"
$PN"2"45;
"A"
$PN"1"39;
%"Q_RES"
"1","(-5600,4300)","2","pure_quanta","I32";
;
LOCATION"R3714"
$SEC"1"
CDS_SEC"1"
WATTAGE"1/16W"
PACK_TYPE"0402LF"
MATERIAL"CHIP"
TOLERANCE"5%"
VALUE"0"
CDS_LIB"pure_quanta"
PART_NUMBER"CS00002JB13";
"B"
$PN"2"42;
"A"
$PN"1"41;
%"Q_RES"
"1","(-5600,4250)","2","pure_quanta","I33";
;
LOCATION"R3713"
$SEC"1"
CDS_SEC"1"
MATERIAL"CHIP"
VALUE"0"
TOLERANCE"5%"
WATTAGE"1/16W"
CDS_LIB"pure_quanta"
PACK_TYPE"0402LF"
PART_NUMBER"CS00002JB13";
"B"
$PN"2"43;
"A"
$PN"1"40;
%"UNIVERSAL_GND"
"1","(-5150,4800)","0","pure_quanta_power","I37";
;
CDS_LIB"pure_quanta_power"
HDL_POWER"GND";
"A"4;
%"Q_CAP"
"1","(-5150,5025)","0","pure_quanta","I38";
;
LOCATION"C2056"
$SEC"1"
CDS_SEC"1"
PACK_TYPE"0402"
MATERIAL"X7R"
TOLERANCE"10%"
VALUE"0.1UF"
VOLTAGE"25V"
CDS_LIB"pure_quanta"
PART_NUMBER"CH4104K1B00";
"B"
$PN"2"4;
"A"
$PN"1"21;
%"UNIVERSAL_POWER"
"1","(-5150,5350)","0","pure_quanta_power","I39";
;
HDL_POWER"P3V3_AUX"
CDS_LIB"pure_quanta_power";
"A"21;
%"Q_RES"
"2","(-6300,2200)","0","pure_quanta","I4";
;
LOCATION"R3707"
$SEC"1"
CDS_SEC"1"
TOLERANCE"1%"
WATTAGE"1/16W"
MATERIAL"CHIP"
VALUE"1K"
PACK_TYPE"0402LF"
CDS_LIB"pure_quanta"
PART_NUMBER"CS21002FB06";
"A"
$PN"1"15;
"B"
$PN"2"3;
%"Q_RES"
"1","(-2550,1275)","0","pure_quanta","I40";
;
LOCATION"R4270"
$SEC"1"
CDS_SEC"1"
MATERIAL"EMPTY"
TOLERANCE"5%"
VALUE"2.2K"
CDS_LIB"pure_quanta"
PACK_TYPE"0402LF"
WATTAGE"1/16W"
PART_NUMBER"CS22202JB07";
"B"
$PN"2"7;
"A"
$PN"1"9;
%"Q_RES"
"1","(-2550,1325)","0","pure_quanta","I41";
;
LOCATION"R4269"
$SEC"1"
CDS_SEC"1"
MATERIAL"EMPTY"
PACK_TYPE"0402LF"
TOLERANCE"5%"
VALUE"2.2K"
WATTAGE"1/16W"
CDS_LIB"pure_quanta"
PART_NUMBER"CS22202JB07";
"B"
$PN"2"8;
"A"
$PN"1"9;
%"Q_RES"
"1","(-2550,1525)","0","pure_quanta","I42";
;
LOCATION"R3732"
$SEC"1"
CDS_SEC"1"
TOLERANCE"5%"
MATERIAL"CHIP"
VALUE"2.2K"
WATTAGE"1/16W"
PACK_TYPE"0402LF"
CDS_LIB"pure_quanta"
PART_NUMBER"CS22202JB07";
"B"
$PN"2"55;
"A"
$PN"1"9;
%"Q_RES"
"1","(-2550,1575)","0","pure_quanta","I43";
;
LOCATION"R3731"
$SEC"1"
CDS_SEC"1"
MATERIAL"CHIP"
TOLERANCE"5%"
PACK_TYPE"0402LF"
VALUE"2.2K"
WATTAGE"1/16W"
CDS_LIB"pure_quanta"
PART_NUMBER"CS22202JB07";
"B"
$PN"2"24;
"A"
$PN"1"9;
%"Q_RES"
"1","(-2550,1875)","0","pure_quanta","I44";
;
LOCATION"R3729"
$SEC"1"
CDS_SEC"1"
TOLERANCE"5%"
MATERIAL"CHIP"
PACK_TYPE"0402LF"
WATTAGE"1/16W"
VALUE"2.2K"
CDS_LIB"pure_quanta"
PART_NUMBER"CS22202JB07";
"B"
$PN"2"25;
"A"
$PN"1"9;
%"Q_RES"
"1","(-2550,1825)","0","pure_quanta","I45";
;
LOCATION"R3730"
$SEC"1"
CDS_SEC"1"
MATERIAL"CHIP"
TOLERANCE"5%"
VALUE"2.2K"
CDS_LIB"pure_quanta"
PACK_TYPE"0402LF"
WATTAGE"1/16W"
PART_NUMBER"CS22202JB07";
"B"
$PN"2"19;
"A"
$PN"1"9;
%"UNIVERSAL_GND"
"1","(-3825,3675)","0","pure_quanta_power","I46";
;
CDS_LIB"pure_quanta_power"
HDL_POWER"GND";
"A"5;
%"Q_RES"
"1","(-2575,2125)","0","pure_quanta","I47";
;
LOCATION"R3728"
$SEC"1"
CDS_SEC"1"
MATERIAL"CHIP"
VALUE"2.2K"
TOLERANCE"5%"
CDS_LIB"pure_quanta"
PACK_TYPE"0402LF"
WATTAGE"1/16W"
PART_NUMBER"CS22202JB07";
"B"
$PN"2"23;
"A"
$PN"1"9;
%"Q_RES"
"1","(-2575,2175)","0","pure_quanta","I48";
;
LOCATION"R3727"
$SEC"1"
CDS_SEC"1"
PACK_TYPE"0402LF"
VALUE"2.2K"
TOLERANCE"5%"
WATTAGE"1/16W"
MATERIAL"CHIP"
CDS_LIB"pure_quanta"
PART_NUMBER"CS22202JB07";
"B"
$PN"2"18;
"A"
$PN"1"9;
%"Q_RES"
"1","(-2575,2400)","0","pure_quanta","I49";
;
LOCATION"R3726"
$SEC"1"
CDS_SEC"1"
TOLERANCE"5%"
MATERIAL"CHIP"
VALUE"2.2K"
WATTAGE"1/16W"
PACK_TYPE"0402LF"
CDS_LIB"pure_quanta"
PART_NUMBER"CS22202JB07";
"B"
$PN"2"22;
"A"
$PN"1"9;
%"UNIVERSAL_GND"
"1","(-6025,1975)","0","pure_quanta_power","I5";
;
ROOM"IO_SLOT"
CDS_LIB"pure_quanta_power"
HDL_POWER"GND";
"A"6;
%"Q_RES"
"1","(-2575,2450)","0","pure_quanta","I50";
;
LOCATION"R3725"
$SEC"1"
CDS_SEC"1"
PACK_TYPE"0402LF"
TOLERANCE"5%"
MATERIAL"CHIP"
WATTAGE"1/16W"
VALUE"2.2K"
CDS_LIB"pure_quanta"
PART_NUMBER"CS22202JB07";
"B"
$PN"2"17;
"A"
$PN"1"9;
%"UNIVERSAL_POWER"
"1","(-3000,3025)","0","pure_quanta_power","I51";
;
HDL_POWER"P3V3_AUX"
CDS_LIB"pure_quanta_power";
"A"9;
%"Q_RES"
"1","(-2575,2775)","0","pure_quanta","I52";
;
LOCATION"R3724"
$SEC"1"
CDS_SEC"1"
TOLERANCE"5%"
MATERIAL"CHIP"
VALUE"2.2K"
CDS_LIB"pure_quanta"
PACK_TYPE"0402LF"
WATTAGE"1/16W"
PART_NUMBER"CS22202JB07";
"B"
$PN"2"12;
"A"
$PN"1"9;
%"Q_RES"
"1","(-2575,2825)","0","pure_quanta","I53";
;
LOCATION"R3723"
$SEC"1"
CDS_SEC"1"
PACK_TYPE"0402LF"
MATERIAL"CHIP"
WATTAGE"1/16W"
VALUE"2.2K"
TOLERANCE"5%"
CDS_LIB"pure_quanta"
PART_NUMBER"CS22202JB07";
"B"
$PN"2"13;
"A"
$PN"1"9;
%"Q_RES"
"2","(-6025,2200)","0","pure_quanta","I6";
;
LOCATION"R3709"
$SEC"1"
CDS_SEC"1"
PACK_TYPE"0402LF"
TOLERANCE"1%"
VALUE"1K"
MATERIAL"CHIP"
WATTAGE"1/16W"
CDS_LIB"pure_quanta"
PART_NUMBER"CS21002FB06";
"A"
$PN"1"14;
"B"
$PN"2"6;
%"Q_RES"
"1","(-2950,4300)","0","pure_quanta","I66";
;
LOCATION"R3722"
$SEC"1"
CDS_SEC"1"
TOLERANCE"5%"
MATERIAL"CHIP"
VALUE"0"
WATTAGE"1/16W"
PACK_TYPE"0402LF"
CDS_LIB"pure_quanta"
PART_NUMBER"CS00002JB13";
"B"
$PN"2"59;
"A"
$PN"1"33;
%"Q_RES"
"1","(-2950,4250)","0","pure_quanta","I67";
;
LOCATION"R3721"
$SEC"1"
CDS_SEC"1"
MATERIAL"CHIP"
TOLERANCE"5%"
VALUE"0"
CDS_LIB"pure_quanta"
WATTAGE"1/16W"
PACK_TYPE"0402LF"
PART_NUMBER"CS00002JB13";
"B"
$PN"2"62;
"A"
$PN"1"31;
%"Q_RES"
"1","(-2825,4550)","2","pure_quanta","I68";
;
LOCATION"R3712"
$SEC"1"
CDS_SEC"1"
MATERIAL"CHIP"
TOLERANCE"1%"
VALUE"33.2"
PACK_TYPE"0402LF"
CDS_LIB"pure_quanta"
WATTAGE"1/16W"
PART_NUMBER"CS03322FB03";
"B"
$PN"2"58;
"A"
$PN"1"57;
%"Q_RES"
"1","(-2825,4500)","2","pure_quanta","I69";
;
LOCATION"R3711"
$SEC"1"
CDS_SEC"1"
WATTAGE"1/16W"
MATERIAL"CHIP"
TOLERANCE"1%"
VALUE"33.2"
PACK_TYPE"0402LF"
CDS_LIB"pure_quanta"
PART_NUMBER"CS03322FB03";
"B"
$PN"2"60;
"A"
$PN"1"26;
%"Q_RES"
"2","(-6575,2850)","0","pure_quanta","I7";
;
LOCATION"R3703"
$SEC"1"
CDS_SEC"1"
WATTAGE"1/16W"
VALUE"10K"
PACK_TYPE"0402LF"
TOLERANCE"1%"
MATERIAL"EMPTY"
CDS_LIB"pure_quanta"
PART_NUMBER"CS31002FB08";
"A"
$PN"1"20;
"B"
$PN"2"63;
%"TCA9548APWR"
"1","(-4275,4275)","0","pure_quanta","I74";
;
LOCATION"U39"
SEC"1"
MATERIAL"IC"
PART_TYPE"SMLF"
VALUE"TCA9548APWR"
CDS_LIB"pure_quanta"
CDS_LMAN_SYM_OUTLINE"-200,475,200,-475"
NEEDS_NO_SIZE"TRUE"
SEC_TYPE""
PART_NUMBER"AL009548K02";
"SD4"
$PN"13"33;
"SC4"
$PN"14"31;
"SD5"
$PN"15"30;
"SC5"
$PN"16"29;
"SD6"
$PN"17"27;
"SC6"
$PN"18"28;
"SD7"
$PN"19"0;
"SC7"
$PN"20"0;
"A2"
$PN"21"61;
"SCL"
$PN"22"60;
"SDA"
$PN"23"58;
"VCC"
$PN"24"21;
"GND"
$PN"12"5;
"SC3"
$PN"11"37;
"SD3"
$PN"10"36;
"SC2"
$PN"9"51;
"SD2"
$PN"8"50;
"SC1"
$PN"7"39;
"SD1"
$PN"6"38;
"SC0"
$PN"5"40;
"SD0"
$PN"4"41;
"RESET# \B"
$PN"3"52;
"A1"
$PN"2"53;
"A0"
$PN"1"54;
%"Q_RES"
"1","(-2950,4200)","0","pure_quanta","I75";
;
LOCATION"R6228"
$SEC"1"
CDS_SEC"1"
MATERIAL"CHIP"
VALUE"0"
TOLERANCE"5%"
CDS_LIB"pure_quanta"
PACK_TYPE"0402LF"
WATTAGE"1/16W"
PART_NUMBER"CS00002JB13";
"B"
$PN"2"35;
"A"
$PN"1"30;
%"Q_RES"
"1","(-2950,4150)","0","pure_quanta","I76";
;
LOCATION"R6229"
$SEC"1"
CDS_SEC"1"
TOLERANCE"5%"
MATERIAL"CHIP"
VALUE"0"
CDS_LIB"pure_quanta"
PACK_TYPE"0402LF"
WATTAGE"1/16W"
PART_NUMBER"CS00002JB13";
"B"
$PN"2"32;
"A"
$PN"1"29;
%"Q_RES"
"1","(-2950,4100)","0","pure_quanta","I79";
;
LOCATION"R1312"
$SEC"1"
CDS_SEC"1"
VALUE"0"
TOLERANCE"5%"
MATERIAL"CHIP"
CDS_LIB"pure_quanta"
PACK_TYPE"0402LF"
WATTAGE"1/16W"
PART_NUMBER"CS00002JB13";
"B"
$PN"2"34;
"A"
$PN"1"27;
%"Q_RES"
"2","(-6300,2850)","0","pure_quanta","I8";
;
LOCATION"R3706"
$SEC"1"
CDS_SEC"1"
VALUE"10K"
WATTAGE"1/16W"
TOLERANCE"1%"
MATERIAL"EMPTY"
PACK_TYPE"0402LF"
CDS_LIB"pure_quanta"
PART_NUMBER"CS31002FB08";
"A"
$PN"1"20;
"B"
$PN"2"15;
%"Q_RES"
"1","(-2950,4050)","0","pure_quanta","I80";
;
LOCATION"R1315"
$SEC"1"
CDS_SEC"1"
TOLERANCE"5%"
VALUE"0"
MATERIAL"CHIP"
WATTAGE"1/16W"
PACK_TYPE"0402LF"
CDS_LIB"pure_quanta"
PART_NUMBER"CS00002JB13";
"B"
$PN"2"16;
"A"
$PN"1"28;
%"Q_RES"
"1","(-2525,800)","0","pure_quanta","I83";
;
LOCATION"R1316"
$SEC"1"
CDS_SEC"1"
VALUE"2.2K"
MATERIAL"CHIP"
TOLERANCE"5%"
PACK_TYPE"0402LF"
WATTAGE"1/16W"
CDS_LIB"pure_quanta"
PART_NUMBER"CS22202JB07";
"B"
$PN"2"10;
"A"
$PN"1"9;
%"Q_RES"
"1","(-2525,750)","0","pure_quanta","I84";
;
LOCATION"R1341"
$SEC"1"
CDS_SEC"1"
TOLERANCE"5%"
MATERIAL"CHIP"
VALUE"2.2K"
CDS_LIB"pure_quanta"
PACK_TYPE"0402LF"
WATTAGE"1/16W"
PART_NUMBER"CS22202JB07";
"B"
$PN"2"11;
"A"
$PN"1"9;
%"UNIVERSAL_POWER"
"1","(-6575,3225)","0","pure_quanta_power","I9";
;
HDL_POWER"P3V3_AUX"
CDS_LIB"pure_quanta_power";
"A"20;
END.
